(kicad_pcb
	(version 20260206)
	(generator "pcbnew")
	(generator_version "10.0")
	(general
		(thickness 1.6)
		(legacy_teardrops no)
	)
	(paper "A4")
	(title_block
		(title "v1-chassis-manager — T6M_CM_d_v01_1031_1645.brd")
		(comment 1 "Open CloudServer (Microsoft) / footprints 2092-2102 of 2512")
	)
	(layers
		(0 "F.Cu" signal "TOP")
		(4 "In1.Cu" signal "GND1")
		(6 "In2.Cu" signal "IN1")
		(8 "In3.Cu" signal "VCC1")
		(10 "In4.Cu" signal "VCC2")
		(12 "In5.Cu" signal "GND2")
		(14 "In6.Cu" signal "IN2")
		(16 "In7.Cu" signal "IN3")
		(18 "In8.Cu" signal "GND3")
		(2 "B.Cu" signal "BOTTOM")
		(9 "F.Adhes" user "F.Adhesive")
		(11 "B.Adhes" user "B.Adhesive")
		(13 "F.Paste" user "Package Geometry/Pastemask Top")
		(15 "B.Paste" user "Package Geometry/Pastemask Bottom")
		(5 "F.SilkS" user "Ref Des/Silkscreen Top")
		(7 "B.SilkS" user "Ref Des/Silkscreen Bottom")
		(1 "F.Mask" user "Board Geometry/Soldermask Top")
		(3 "B.Mask" user "Board Geometry/Soldermask Bottom")
		(17 "Dwgs.User" user "User.Drawings")
		(19 "Cmts.User" user "User.Comments")
		(21 "Eco1.User" user "User.Eco1")
		(23 "Eco2.User" user "User.Eco2")
		(25 "Edge.Cuts" user "Board Geometry/Outline")
		(27 "Margin" user)
		(31 "F.CrtYd" user "Package Geometry/Place Bound Top")
		(29 "B.CrtYd" user "Package Geometry/Place Bound Bottom")
		(35 "F.Fab" user "Ref Des/Assembly Top")
		(33 "B.Fab" user "Ref Des/Assembly Bottom")
	)
	(footprint ""
		(layer "B.Cu")
		(at 47.10176 -188.126624 -90)
		(property "Reference" "R858"
			(at -4.318254 0.408432 270)
			(unlocked yes)
			(layer "B.SilkS")
			(effects
				(font
					(size 0.7874 0.5842)
					(thickness 0.1524)
				)
				(justify left mirror)
			)
		)
		(property "Value" ""
			(at 0 0 90)
			(layer "B.Fab")
			(effects
				(font
					(size 1.27 1.27)
				)
				(justify mirror)
			)
		)
		(duplicate_pad_numbers_are_jumpers no)
		(fp_line
			(start -0.7874 0.4064)
			(end 0.7874 0.4064)
			(stroke
				(width 0.1524)
				(type default)
			)
			(layer "B.SilkS")
		)
		(fp_line
			(start 0.7874 0.4064)
			(end 0.7874 -0.4064)
			(stroke
				(width 0.1524)
				(type default)
			)
			(layer "B.SilkS")
		)
		(fp_line
			(start -0.7874 -0.4064)
			(end -0.7874 0.4064)
			(stroke
				(width 0.1524)
				(type default)
			)
			(layer "B.SilkS")
		)
		(fp_line
			(start 0.7874 -0.4064)
			(end -0.7874 -0.4064)
			(stroke
				(width 0.1524)
				(type default)
			)
			(layer "B.SilkS")
		)
		(fp_poly
			(pts
				(xy 0.508 0.2794) (xy 0.508 0.2286) (xy 0.635 0.2286) (xy 0.635 -0.254) (xy 0.5334 -0.254) (xy 0.5334 -0.2794)
				(xy -0.5334 -0.2794) (xy -0.5334 -0.254) (xy -0.635 -0.254) (xy -0.635 0.254) (xy -0.5334 0.254)
				(xy -0.5334 0.2794)
			)
			(stroke
				(width 0)
				(type default)
			)
			(fill no)
			(layer "B.CrtYd")
		)
		(pad "1" smd rect
			(at -0.40005 0 90)
			(size 0.4572 0.508)
			(layers "B.Cu" "B.Mask" "B.Paste")
			(net "PSU6_DC_OK_R")
		)
		(pad "2" smd rect
			(at 0.40005 0 90)
			(size 0.4572 0.508)
			(layers "B.Cu" "B.Mask" "B.Paste")
			(net "GND")
		)
	)
	(footprint ""
		(layer "B.Cu")
		(at 165.77564 -188.19749 -90)
		(property "Reference" "C613"
			(at -2.15011 0.16891 270)
			(unlocked yes)
			(layer "B.SilkS")
			(effects
				(font
					(size 0.7874 0.5842)
					(thickness 0.1524)
				)
				(justify left mirror)
			)
		)
		(property "Value" ""
			(at 0 0 90)
			(layer "B.Fab")
			(effects
				(font
					(size 1.27 1.27)
				)
				(justify mirror)
			)
		)
		(duplicate_pad_numbers_are_jumpers no)
		(fp_line
			(start -0.7874 0.4064)
			(end 0.7874 0.4064)
			(stroke
				(width 0.1524)
				(type default)
			)
			(layer "B.SilkS")
		)
		(fp_line
			(start 0.7874 0.4064)
			(end 0.7874 -0.4064)
			(stroke
				(width 0.1524)
				(type default)
			)
			(layer "B.SilkS")
		)
		(fp_line
			(start 0 0.381)
			(end 0 -0.381)
			(stroke
				(width 0.1524)
				(type default)
			)
			(layer "B.SilkS")
		)
		(fp_line
			(start -0.7874 -0.4064)
			(end -0.7874 0.4064)
			(stroke
				(width 0.1524)
				(type default)
			)
			(layer "B.SilkS")
		)
		(fp_line
			(start 0.7874 -0.4064)
			(end -0.7874 -0.4064)
			(stroke
				(width 0.1524)
				(type default)
			)
			(layer "B.SilkS")
		)
		(fp_poly
			(pts
				(xy 0.5334 0.254) (xy 0.635 0.254) (xy 0.635 0.2286) (xy 0.635 -0.254) (xy 0.5334 -0.254) (xy 0.5334 -0.2794)
				(xy -0.5334 -0.2794) (xy -0.5334 -0.254) (xy -0.635 -0.254) (xy -0.635 0.254) (xy -0.5334 0.254)
				(xy -0.5334 0.2794) (xy 0.508 0.2794) (xy 0.5334 0.2794)
			)
			(stroke
				(width 0)
				(type default)
			)
			(fill no)
			(layer "B.CrtYd")
		)
		(pad "1" smd rect
			(at -0.40005 0 90)
			(size 0.4572 0.508)
			(layers "B.Cu" "B.Mask" "B.Paste")
			(net "I2C_PDB_R_SDA")
		)
		(pad "2" smd rect
			(at 0.40005 0 90)
			(size 0.4572 0.508)
			(layers "B.Cu" "B.Mask" "B.Paste")
			(net "GND")
		)
	)
	(footprint ""
		(layer "B.Cu")
		(at 139.717272 -163.363402 180)
		(property "Reference" "R989"
			(at 0.583946 -4.085844 270)
			(unlocked yes)
			(layer "B.SilkS")
			(effects
				(font
					(size 0.7874 0.5842)
					(thickness 0.1524)
				)
				(justify left mirror)
			)
		)
		(property "Value" ""
			(at 0 0 0)
			(layer "B.Fab")
			(effects
				(font
					(size 1.27 1.27)
				)
				(justify mirror)
			)
		)
		(duplicate_pad_numbers_are_jumpers no)
		(fp_line
			(start 0.7874 0.4064)
			(end 0.7874 -0.4064)
			(stroke
				(width 0.1524)
				(type default)
			)
			(layer "B.SilkS")
		)
		(fp_line
			(start 0.7874 -0.4064)
			(end -0.7874 -0.4064)
			(stroke
				(width 0.1524)
				(type default)
			)
			(layer "B.SilkS")
		)
		(fp_line
			(start -0.7874 0.4064)
			(end 0.7874 0.4064)
			(stroke
				(width 0.1524)
				(type default)
			)
			(layer "B.SilkS")
		)
		(fp_line
			(start -0.7874 -0.4064)
			(end -0.7874 0.4064)
			(stroke
				(width 0.1524)
				(type default)
			)
			(layer "B.SilkS")
		)
		(fp_poly
			(pts
				(xy 0.508 0.2794) (xy 0.508 0.2286) (xy 0.635 0.2286) (xy 0.635 -0.254) (xy 0.5334 -0.254) (xy 0.5334 -0.2794)
				(xy -0.5334 -0.2794) (xy -0.5334 -0.254) (xy -0.635 -0.254) (xy -0.635 0.254) (xy -0.5334 0.254)
				(xy -0.5334 0.2794)
			)
			(stroke
				(width 0)
				(type default)
			)
			(fill no)
			(layer "B.CrtYd")
		)
		(pad "1" smd rect
			(at -0.40005 0)
			(size 0.4572 0.508)
			(layers "B.Cu" "B.Mask" "B.Paste")
			(net "UART_T10_NODE2_TXD")
		)
		(pad "2" smd rect
			(at 0.40005 0)
			(size 0.4572 0.508)
			(layers "B.Cu" "B.Mask" "B.Paste")
			(net "UART_T10_NODE2_TXD_R")
		)
	)
	(footprint ""
		(layer "B.Cu")
		(at 79.0194 -162.340544)
		(property "Reference" "C579"
			(at 2.930144 1.514602 0)
			(unlocked yes)
			(layer "B.SilkS")
			(effects
				(font
					(size 0.7874 0.5842)
					(thickness 0.1524)
				)
				(justify left mirror)
			)
		)
		(property "Value" ""
			(at 0 0 0)
			(layer "B.Fab")
			(effects
				(font
					(size 1.27 1.27)
				)
				(justify mirror)
			)
		)
		(duplicate_pad_numbers_are_jumpers no)
		(fp_line
			(start -0.7874 -0.4064)
			(end -0.7874 0.4064)
			(stroke
				(width 0.1524)
				(type default)
			)
			(layer "B.SilkS")
		)
		(fp_line
			(start -0.7874 0.4064)
			(end 0.7874 0.4064)
			(stroke
				(width 0.1524)
				(type default)
			)
			(layer "B.SilkS")
		)
		(fp_line
			(start 0 0.381)
			(end 0 -0.381)
			(stroke
				(width 0.1524)
				(type default)
			)
			(layer "B.SilkS")
		)
		(fp_line
			(start 0.7874 -0.4064)
			(end -0.7874 -0.4064)
			(stroke
				(width 0.1524)
				(type default)
			)
			(layer "B.SilkS")
		)
		(fp_line
			(start 0.7874 0.4064)
			(end 0.7874 -0.4064)
			(stroke
				(width 0.1524)
				(type default)
			)
			(layer "B.SilkS")
		)
		(fp_poly
			(pts
				(xy 0.5334 0.254) (xy 0.635 0.254) (xy 0.635 0.2286) (xy 0.635 -0.254) (xy 0.5334 -0.254) (xy 0.5334 -0.2794)
				(xy -0.5334 -0.2794) (xy -0.5334 -0.254) (xy -0.635 -0.254) (xy -0.635 0.254) (xy -0.5334 0.254)
				(xy -0.5334 0.2794) (xy 0.508 0.2794) (xy 0.5334 0.2794)
			)
			(stroke
				(width 0)
				(type default)
			)
			(fill no)
			(layer "B.CrtYd")
		)
		(pad "1" smd rect
			(at -0.40005 0 180)
			(size 0.4572 0.508)
			(layers "B.Cu" "B.Mask" "B.Paste")
			(net "GND")
		)
		(pad "2" smd rect
			(at 0.40005 0 180)
			(size 0.4572 0.508)
			(layers "B.Cu" "B.Mask" "B.Paste")
			(net "P3V3_NODE1")
		)
	)
	(footprint ""
		(layer "B.Cu")
		(at 141.08176 -184.951624 90)
		(property "Reference" "R978"
			(at 4.357624 -2.102612 270)
			(unlocked yes)
			(layer "B.SilkS")
			(effects
				(font
					(size 0.7874 0.5842)
					(thickness 0.1524)
				)
				(justify left mirror)
			)
		)
		(property "Value" ""
			(at 0 0 90)
			(layer "B.Fab")
			(effects
				(font
					(size 1.27 1.27)
				)
				(justify mirror)
			)
		)
		(duplicate_pad_numbers_are_jumpers no)
		(fp_line
			(start 0.7874 -0.4064)
			(end -0.7874 -0.4064)
			(stroke
				(width 0.1524)
				(type default)
			)
			(layer "B.SilkS")
		)
		(fp_line
			(start -0.7874 -0.4064)
			(end -0.7874 0.4064)
			(stroke
				(width 0.1524)
				(type default)
			)
			(layer "B.SilkS")
		)
		(fp_line
			(start 0.7874 0.4064)
			(end 0.7874 -0.4064)
			(stroke
				(width 0.1524)
				(type default)
			)
			(layer "B.SilkS")
		)
		(fp_line
			(start -0.7874 0.4064)
			(end 0.7874 0.4064)
			(stroke
				(width 0.1524)
				(type default)
			)
			(layer "B.SilkS")
		)
		(fp_poly
			(pts
				(xy 0.508 0.2794) (xy 0.508 0.2286) (xy 0.635 0.2286) (xy 0.635 -0.254) (xy 0.5334 -0.254) (xy 0.5334 -0.2794)
				(xy -0.5334 -0.2794) (xy -0.5334 -0.254) (xy -0.635 -0.254) (xy -0.635 0.254) (xy -0.5334 0.254)
				(xy -0.5334 0.2794)
			)
			(stroke
				(width 0)
				(type default)
			)
			(fill no)
			(layer "B.CrtYd")
		)
		(pad "1" smd rect
			(at -0.40005 0 270)
			(size 0.4572 0.508)
			(layers "B.Cu" "B.Mask" "B.Paste")
			(net "UART_T11_NODE4_TXD")
		)
		(pad "2" smd rect
			(at 0.40005 0 270)
			(size 0.4572 0.508)
			(layers "B.Cu" "B.Mask" "B.Paste")
			(net "UART_T11_NODE4_TXD_R")
		)
	)
	(footprint ""
		(layer "B.Cu")
		(at 137.245852 -151.28875 90)
		(property "Reference" "C881"
			(at 1.03124 3.336798 270)
			(unlocked yes)
			(layer "B.SilkS")
			(effects
				(font
					(size 0.7874 0.5842)
					(thickness 0.1524)
				)
				(justify left mirror)
			)
		)
		(property "Value" ""
			(at 0 0 90)
			(layer "B.Fab")
			(effects
				(font
					(size 1.27 1.27)
				)
				(justify mirror)
			)
		)
		(duplicate_pad_numbers_are_jumpers no)
		(fp_line
			(start 0.7874 -0.4064)
			(end -0.7874 -0.4064)
			(stroke
				(width 0.1524)
				(type default)
			)
			(layer "B.SilkS")
		)
		(fp_line
			(start -0.7874 -0.4064)
			(end -0.7874 0.4064)
			(stroke
				(width 0.1524)
				(type default)
			)
			(layer "B.SilkS")
		)
		(fp_line
			(start 0 0.381)
			(end 0 -0.381)
			(stroke
				(width 0.1524)
				(type default)
			)
			(layer "B.SilkS")
		)
		(fp_line
			(start 0.7874 0.4064)
			(end 0.7874 -0.4064)
			(stroke
				(width 0.1524)
				(type default)
			)
			(layer "B.SilkS")
		)
		(fp_line
			(start -0.7874 0.4064)
			(end 0.7874 0.4064)
			(stroke
				(width 0.1524)
				(type default)
			)
			(layer "B.SilkS")
		)
		(fp_poly
			(pts
				(xy 0.5334 0.254) (xy 0.635 0.254) (xy 0.635 0.2286) (xy 0.635 -0.254) (xy 0.5334 -0.254) (xy 0.5334 -0.2794)
				(xy -0.5334 -0.2794) (xy -0.5334 -0.254) (xy -0.635 -0.254) (xy -0.635 0.254) (xy -0.5334 0.254)
				(xy -0.5334 0.2794) (xy 0.508 0.2794) (xy 0.5334 0.2794)
			)
			(stroke
				(width 0)
				(type default)
			)
			(fill no)
			(layer "B.CrtYd")
		)
		(pad "1" smd rect
			(at -0.40005 0 270)
			(size 0.4572 0.508)
			(layers "B.Cu" "B.Mask" "B.Paste")
			(net "P3V3_NODE1")
		)
		(pad "2" smd rect
			(at 0.40005 0 270)
			(size 0.4572 0.508)
			(layers "B.Cu" "B.Mask" "B.Paste")
			(net "GND")
		)
	)
	(footprint ""
		(layer "B.Cu")
		(at 79.948024 -96.258634)
		(property "Reference" "R139"
			(at 3.854196 0.039624 0)
			(unlocked yes)
			(layer "B.SilkS")
			(effects
				(font
					(size 0.7874 0.5842)
					(thickness 0.1524)
				)
				(justify left mirror)
			)
		)
		(property "Value" ""
			(at 0 0 0)
			(layer "B.Fab")
			(effects
				(font
					(size 1.27 1.27)
				)
				(justify mirror)
			)
		)
		(duplicate_pad_numbers_are_jumpers no)
		(fp_line
			(start -0.7874 -0.4064)
			(end -0.7874 0.4064)
			(stroke
				(width 0.1524)
				(type default)
			)
			(layer "B.SilkS")
		)
		(fp_line
			(start -0.7874 0.4064)
			(end 0.7874 0.4064)
			(stroke
				(width 0.1524)
				(type default)
			)
			(layer "B.SilkS")
		)
		(fp_line
			(start 0.7874 -0.4064)
			(end -0.7874 -0.4064)
			(stroke
				(width 0.1524)
				(type default)
			)
			(layer "B.SilkS")
		)
		(fp_line
			(start 0.7874 0.4064)
			(end 0.7874 -0.4064)
			(stroke
				(width 0.1524)
				(type default)
			)
			(layer "B.SilkS")
		)
		(fp_poly
			(pts
				(xy 0.508 0.2794) (xy 0.508 0.2286) (xy 0.635 0.2286) (xy 0.635 -0.254) (xy 0.5334 -0.254) (xy 0.5334 -0.2794)
				(xy -0.5334 -0.2794) (xy -0.5334 -0.254) (xy -0.635 -0.254) (xy -0.635 0.254) (xy -0.5334 0.254)
				(xy -0.5334 0.2794)
			)
			(stroke
				(width 0)
				(type default)
			)
			(fill no)
			(layer "B.CrtYd")
		)
		(pad "1" smd rect
			(at -0.40005 0 180)
			(size 0.4572 0.508)
			(layers "B.Cu" "B.Mask" "B.Paste")
			(net "CLK_33K_CPU_NODE1_SUSCLK")
		)
		(pad "2" smd rect
			(at 0.40005 0 180)
			(size 0.4572 0.508)
			(layers "B.Cu" "B.Mask" "B.Paste")
			(net "CLK_33K_CPU_NODE1_SUSCLK_RR")
		)
	)
	(footprint ""
		(layer "B.Cu")
		(at 88.77935 -78.765654 180)
		(property "Reference" "R173"
			(at 1.91516 -9.611614 0)
			(unlocked yes)
			(layer "B.SilkS")
			(effects
				(font
					(size 0.7874 0.5842)
					(thickness 0.1524)
				)
				(justify left mirror)
			)
		)
		(property "Value" ""
			(at 0 0 0)
			(layer "B.Fab")
			(effects
				(font
					(size 1.27 1.27)
				)
				(justify mirror)
			)
		)
		(duplicate_pad_numbers_are_jumpers no)
		(fp_line
			(start 0.7874 0.4064)
			(end 0.7874 -0.4064)
			(stroke
				(width 0.1524)
				(type default)
			)
			(layer "B.SilkS")
		)
		(fp_line
			(start 0.7874 -0.4064)
			(end -0.7874 -0.4064)
			(stroke
				(width 0.1524)
				(type default)
			)
			(layer "B.SilkS")
		)
		(fp_line
			(start -0.7874 0.4064)
			(end 0.7874 0.4064)
			(stroke
				(width 0.1524)
				(type default)
			)
			(layer "B.SilkS")
		)
		(fp_line
			(start -0.7874 -0.4064)
			(end -0.7874 0.4064)
			(stroke
				(width 0.1524)
				(type default)
			)
			(layer "B.SilkS")
		)
		(fp_poly
			(pts
				(xy 0.508 0.2794) (xy 0.508 0.2286) (xy 0.635 0.2286) (xy 0.635 -0.254) (xy 0.5334 -0.254) (xy 0.5334 -0.2794)
				(xy -0.5334 -0.2794) (xy -0.5334 -0.254) (xy -0.635 -0.254) (xy -0.635 0.254) (xy -0.5334 0.254)
				(xy -0.5334 0.2794)
			)
			(stroke
				(width 0)
				(type default)
			)
			(fill no)
			(layer "B.CrtYd")
		)
		(pad "1" smd rect
			(at -0.40005 0)
			(size 0.4572 0.508)
			(layers "B.Cu" "B.Mask" "B.Paste")
			(net "GND")
		)
		(pad "2" smd rect
			(at 0.40005 0)
			(size 0.4572 0.508)
			(layers "B.Cu" "B.Mask" "B.Paste")
			(net "PU_CPU_NODE1_MEM_SPEED0")
		)
	)
	(footprint ""
		(layer "B.Cu")
		(at 165.420548 -199.03567)
		(property "Reference" "TP9"
			(at 0 0 0)
			(layer "B.SilkS")
			(hide yes)
			(effects
				(font
					(size 1.27 1.27)
				)
				(justify mirror)
			)
		)
		(property "Value" ""
			(at 0 0 0)
			(layer "B.Fab")
			(effects
				(font
					(size 1.27 1.27)
				)
				(justify mirror)
			)
		)
		(duplicate_pad_numbers_are_jumpers no)
		(fp_poly
			(pts
				(arc
					(start 0.381 0)
					(mid -0.381 0)
					(end 0.381 0)
				)
			)
			(stroke
				(width 0)
				(type default)
			)
			(fill no)
			(layer "B.CrtYd")
		)
		(pad "1" smd circle
			(at 0 0 180)
			(size 0.762 0.762)
			(layers "B.Cu" "B.Mask" "B.Paste")
			(net "UART_DSR_RP5_L")
		)
	)
	(footprint ""
		(layer "B.Cu")
		(at 32.639 -188.7728)
		(property "Reference" "R1332"
			(at 1.7018 -0.98933 0)
			(unlocked yes)
			(layer "B.SilkS")
			(effects
				(font
					(size 0.7874 0.5842)
					(thickness 0.1524)
				)
				(justify left mirror)
			)
		)
		(property "Value" ""
			(at 0 0 0)
			(layer "B.Fab")
			(effects
				(font
					(size 1.27 1.27)
				)
				(justify mirror)
			)
		)
		(duplicate_pad_numbers_are_jumpers no)
		(fp_line
			(start -0.7874 -0.4064)
			(end -0.7874 0.4064)
			(stroke
				(width 0.1524)
				(type default)
			)
			(layer "B.SilkS")
		)
		(fp_line
			(start -0.7874 0.4064)
			(end 0.7874 0.4064)
			(stroke
				(width 0.1524)
				(type default)
			)
			(layer "B.SilkS")
		)
		(fp_line
			(start 0.7874 -0.4064)
			(end -0.7874 -0.4064)
			(stroke
				(width 0.1524)
				(type default)
			)
			(layer "B.SilkS")
		)
		(fp_line
			(start 0.7874 0.4064)
			(end 0.7874 -0.4064)
			(stroke
				(width 0.1524)
				(type default)
			)
			(layer "B.SilkS")
		)
		(fp_poly
			(pts
				(xy 0.508 0.2794) (xy 0.508 0.2286) (xy 0.635 0.2286) (xy 0.635 -0.254) (xy 0.5334 -0.254) (xy 0.5334 -0.2794)
				(xy -0.5334 -0.2794) (xy -0.5334 -0.254) (xy -0.635 -0.254) (xy -0.635 0.254) (xy -0.5334 0.254)
				(xy -0.5334 0.2794)
			)
			(stroke
				(width 0)
				(type default)
			)
			(fill no)
			(layer "B.CrtYd")
		)
		(pad "1" smd rect
			(at -0.40005 0 180)
			(size 0.4572 0.508)
			(layers "B.Cu" "B.Mask" "B.Paste")
			(net "UART_RI_P5_L_N")
		)
		(pad "2" smd rect
			(at 0.40005 0 180)
			(size 0.4572 0.508)
			(layers "B.Cu" "B.Mask" "B.Paste")
			(net "UART_RI_P5_L_N_R")
		)
	)
	(footprint ""
		(layer "B.Cu")
		(at 141.801596 -37.915596)
		(property "Reference" "R1056"
			(at -3.549396 19.425666 0)
			(unlocked yes)
			(layer "B.SilkS")
			(effects
				(font
					(size 0.7874 0.5842)
					(thickness 0.1524)
				)
				(justify left mirror)
			)
		)
		(property "Value" ""
			(at 0 0 0)
			(layer "B.Fab")
			(effects
				(font
					(size 1.27 1.27)
				)
				(justify mirror)
			)
		)
		(duplicate_pad_numbers_are_jumpers no)
		(fp_line
			(start -0.7874 -0.4064)
			(end -0.7874 0.4064)
			(stroke
				(width 0.1524)
				(type default)
			)
			(layer "B.SilkS")
		)
		(fp_line
			(start -0.7874 0.4064)
			(end 0.7874 0.4064)
			(stroke
				(width 0.1524)
				(type default)
			)
			(layer "B.SilkS")
		)
		(fp_line
			(start 0.7874 -0.4064)
			(end -0.7874 -0.4064)
			(stroke
				(width 0.1524)
				(type default)
			)
			(layer "B.SilkS")
		)
		(fp_line
			(start 0.7874 0.4064)
			(end 0.7874 -0.4064)
			(stroke
				(width 0.1524)
				(type default)
			)
			(layer "B.SilkS")
		)
		(fp_poly
			(pts
				(xy 0.508 0.2794) (xy 0.508 0.2286) (xy 0.635 0.2286) (xy 0.635 -0.254) (xy 0.5334 -0.254) (xy 0.5334 -0.2794)
				(xy -0.5334 -0.2794) (xy -0.5334 -0.254) (xy -0.635 -0.254) (xy -0.635 0.254) (xy -0.5334 0.254)
				(xy -0.5334 0.2794)
			)
			(stroke
				(width 0)
				(type default)
			)
			(fill no)
			(layer "B.CrtYd")
		)
		(pad "1" smd rect
			(at -0.40005 0 180)
			(size 0.4572 0.508)
			(layers "B.Cu" "B.Mask" "B.Paste")
			(net "SIO_JTAG_CPLD2_TDO")
		)
		(pad "2" smd rect
			(at 0.40005 0 180)
			(size 0.4572 0.508)
			(layers "B.Cu" "B.Mask" "B.Paste")
			(net "P3V3_NODE1")
		)
	)
)
